# S9S_MB_2U (Grand Teton) — schematic netlist excerpt (pin names and nets, part order shuffled) for the footprints in the layout excerpt that follows; sources: Cadence DE-HDL packaged netlist, KiCad conversion of 03242023_DA0F0TMBIJ0_F0T_Motherboard_J_brd_V01_OCP.brd

PR261  Q_RES  0 5% CHIP  pkg 0402LF  page 292 : A = P12V_AUX ; B = PVCCINFAON_CPU1_VIN_CSNIN
R1006  Q_RES  4.7K 5% CHIP  pkg 0402LF  page 235 : A = PVNN_TERM_CPU0 ; B = FM_PEHPCPU0_ALERT_N

(kicad_pcb
	(version 20260206)
	(generator "pcbnew")
	(generator_version "10.0")
	(general
		(thickness 1.6)
		(legacy_teardrops no)
	)
	(paper "A4")
	(title_block
		(title "03242023_DA0F0TMBIJ0_F0T_Motherboard_J_brd_V01_OCP.brd")
		(comment 1 "Grand Teton / footprints 4633-4634 of 6105")
	)
	(layers
		(0 "F.Cu" signal "TOP")
		(4 "In1.Cu" signal "GND")
		(6 "In2.Cu" signal "IN1")
		(8 "In3.Cu" signal "GND1")
		(10 "In4.Cu" signal "IN2")
		(12 "In5.Cu" signal "GND2")
		(14 "In6.Cu" signal "IN3")
		(16 "In7.Cu" signal "GND3")
		(18 "In8.Cu" signal "VCC")
		(20 "In9.Cu" signal "VCC1")
		(22 "In10.Cu" signal "GND4")
		(24 "In11.Cu" signal "IN4")
		(26 "In12.Cu" signal "GND5")
		(28 "In13.Cu" signal "IN5")
		(30 "In14.Cu" signal "GND6")
		(32 "In15.Cu" signal "IN6")
		(34 "In16.Cu" signal "GND7")
		(2 "B.Cu" signal "BOTTOM")
		(9 "F.Adhes" user "F.Adhesive")
		(11 "B.Adhes" user "B.Adhesive")
		(13 "F.Paste" user "Package Geometry/Pastemask Top")
		(15 "B.Paste" user "Package Geometry/Pastemask Bottom")
		(5 "F.SilkS" user "Ref Des/Silkscreen Top")
		(7 "B.SilkS" user "Ref Des/Silkscreen Bottom")
		(1 "F.Mask" user "Board Geometry/Soldermask Top")
		(3 "B.Mask" user "Board Geometry/Soldermask Bottom")
		(17 "Dwgs.User" user "User.Drawings")
		(19 "Cmts.User" user "User.Comments")
		(21 "Eco1.User" user "User.Eco1")
		(23 "Eco2.User" user "User.Eco2")
		(25 "Edge.Cuts" user "Board Geometry/Outline")
		(27 "Margin" user)
		(31 "F.CrtYd" user "Package Geometry/Place Bound Top")
		(29 "B.CrtYd" user "Package Geometry/Place Bound Bottom")
		(35 "F.Fab" user "Ref Des/Assembly Top")
		(33 "B.Fab" user "Ref Des/Assembly Bottom")
	)
	(footprint ""
		(layer "B.Cu")
		(at 364.04804 -185.981848 180)
		(property "Reference" "R1006"
			(at 0 0 0)
			(layer "B.SilkS")
			(hide yes)
			(effects
				(font
					(size 1.27 1.27)
				)
				(justify mirror)
			)
		)
		(property "Value" ""
			(at 0 0 0)
			(layer "B.Fab")
			(effects
				(font
					(size 1.27 1.27)
				)
				(justify mirror)
			)
		)
		(duplicate_pad_numbers_are_jumpers no)
		(fp_line
			(start 0.7874 0.4064)
			(end 0.7874 -0.4064)
			(stroke
				(width 0.1524)
				(type default)
			)
			(layer "B.SilkS")
		)
		(fp_line
			(start 0.7874 -0.4064)
			(end -0.7874 -0.4064)
			(stroke
				(width 0.1524)
				(type default)
			)
			(layer "B.SilkS")
		)
		(fp_line
			(start -0.7874 0.4064)
			(end 0.7874 0.4064)
			(stroke
				(width 0.1524)
				(type default)
			)
			(layer "B.SilkS")
		)
		(fp_line
			(start -0.7874 -0.4064)
			(end -0.7874 0.4064)
			(stroke
				(width 0.1524)
				(type default)
			)
			(layer "B.SilkS")
		)
		(fp_line
			(start 0.67945 0.3048)
			(end 0.67945 -0.305054)
			(stroke
				(width 0.1)
				(type default)
			)
			(layer "B.Fab")
		)
		(fp_line
			(start 0.67945 -0.305054)
			(end 0.12065 -0.305054)
			(stroke
				(width 0.1)
				(type default)
			)
			(layer "B.Fab")
		)
		(fp_line
			(start 0.12065 0.3048)
			(end 0.67945 0.3048)
			(stroke
				(width 0.1)
				(type default)
			)
			(layer "B.Fab")
		)
		(fp_line
			(start 0.12065 0.2794)
			(end 0.12065 0.3048)
			(stroke
				(width 0.1)
				(type default)
			)
			(layer "B.Fab")
		)
		(fp_line
			(start 0.12065 -0.2794)
			(end -0.12065 -0.2794)
			(stroke
				(width 0.1)
				(type default)
			)
			(layer "B.Fab")
		)
		(fp_line
			(start 0.12065 -0.305054)
			(end 0.12065 -0.2794)
			(stroke
				(width 0.1)
				(type default)
			)
			(layer "B.Fab")
		)
		(fp_line
			(start -0.120396 0.3048)
			(end -0.120396 0.2794)
			(stroke
				(width 0.1)
				(type default)
			)
			(layer "B.Fab")
		)
		(fp_line
			(start -0.120396 0.2794)
			(end 0.12065 0.2794)
			(stroke
				(width 0.1)
				(type default)
			)
			(layer "B.Fab")
		)
		(fp_line
			(start -0.12065 -0.2794)
			(end -0.12065 -0.3048)
			(stroke
				(width 0.1)
				(type default)
			)
			(layer "B.Fab")
		)
		(fp_line
			(start -0.12065 -0.3048)
			(end -0.67945 -0.3048)
			(stroke
				(width 0.1)
				(type default)
			)
			(layer "B.Fab")
		)
		(fp_line
			(start -0.67945 0.3048)
			(end -0.120396 0.3048)
			(stroke
				(width 0.1)
				(type default)
			)
			(layer "B.Fab")
		)
		(fp_line
			(start -0.67945 -0.3048)
			(end -0.67945 0.3048)
			(stroke
				(width 0.1)
				(type default)
			)
			(layer "B.Fab")
		)
		(pad "1" smd circle
			(at 0.40005 0)
			(size 0 0)
			(layers "B.Cu" "B.Mask" "B.Paste")
			(net "PVNN_TERM_CPU0")
		)
		(pad "2" smd circle
			(at -0.40005 0)
			(size 0 0)
			(layers "B.Cu" "B.Mask" "B.Paste")
			(net "FM_PEHPCPU0_ALERT_N")
		)
	)
	(footprint ""
		(layer "B.Cu")
		(at 27.0383 -128.364996 180)
		(property "Reference" "PR261"
			(at 0 0 0)
			(layer "B.SilkS")
			(hide yes)
			(effects
				(font
					(size 1.27 1.27)
				)
				(justify mirror)
			)
		)
		(property "Value" ""
			(at 0 0 0)
			(layer "B.Fab")
			(effects
				(font
					(size 1.27 1.27)
				)
				(justify mirror)
			)
		)
		(duplicate_pad_numbers_are_jumpers no)
		(fp_line
			(start 0.7874 0.4064)
			(end 0.7874 -0.4064)
			(stroke
				(width 0.1524)
				(type default)
			)
			(layer "B.SilkS")
		)
		(fp_line
			(start 0.7874 -0.4064)
			(end -0.7874 -0.4064)
			(stroke
				(width 0.1524)
				(type default)
			)
			(layer "B.SilkS")
		)
		(fp_line
			(start -0.7874 0.4064)
			(end 0.7874 0.4064)
			(stroke
				(width 0.1524)
				(type default)
			)
			(layer "B.SilkS")
		)
		(fp_line
			(start -0.7874 -0.4064)
			(end -0.7874 0.4064)
			(stroke
				(width 0.1524)
				(type default)
			)
			(layer "B.SilkS")
		)
		(fp_line
			(start 0.67945 0.3048)
			(end 0.67945 -0.305054)
			(stroke
				(width 0.1)
				(type default)
			)
			(layer "B.Fab")
		)
		(fp_line
			(start 0.67945 -0.305054)
			(end 0.12065 -0.305054)
			(stroke
				(width 0.1)
				(type default)
			)
			(layer "B.Fab")
		)
		(fp_line
			(start 0.12065 0.3048)
			(end 0.67945 0.3048)
			(stroke
				(width 0.1)
				(type default)
			)
			(layer "B.Fab")
		)
		(fp_line
			(start 0.12065 0.2794)
			(end 0.12065 0.3048)
			(stroke
				(width 0.1)
				(type default)
			)
			(layer "B.Fab")
		)
		(fp_line
			(start 0.12065 -0.2794)
			(end -0.12065 -0.2794)
			(stroke
				(width 0.1)
				(type default)
			)
			(layer "B.Fab")
		)
		(fp_line
			(start 0.12065 -0.305054)
			(end 0.12065 -0.2794)
			(stroke
				(width 0.1)
				(type default)
			)
			(layer "B.Fab")
		)
		(fp_line
			(start -0.120396 0.3048)
			(end -0.120396 0.2794)
			(stroke
				(width 0.1)
				(type default)
			)
			(layer "B.Fab")
		)
		(fp_line
			(start -0.120396 0.2794)
			(end 0.12065 0.2794)
			(stroke
				(width 0.1)
				(type default)
			)
			(layer "B.Fab")
		)
		(fp_line
			(start -0.12065 -0.2794)
			(end -0.12065 -0.3048)
			(stroke
				(width 0.1)
				(type default)
			)
			(layer "B.Fab")
		)
		(fp_line
			(start -0.12065 -0.3048)
			(end -0.67945 -0.3048)
			(stroke
				(width 0.1)
				(type default)
			)
			(layer "B.Fab")
		)
		(fp_line
			(start -0.67945 0.3048)
			(end -0.120396 0.3048)
			(stroke
				(width 0.1)
				(type default)
			)
			(layer "B.Fab")
		)
		(fp_line
			(start -0.67945 -0.3048)
			(end -0.67945 0.3048)
			(stroke
				(width 0.1)
				(type default)
			)
			(layer "B.Fab")
		)
		(pad "1" smd circle
			(at 0.40005 0)
			(size 0 0)
			(layers "B.Cu" "B.Mask" "B.Paste")
			(net "P12V_AUX")
		)
		(pad "2" smd circle
			(at -0.40005 0)
			(size 0 0)
			(layers "B.Cu" "B.Mask" "B.Paste")
			(net "PVCCINFAON_CPU1_VIN_CSNIN")
		)
	)
)
